(kicad_pcb
	(version 20221018)
	(generator pcbnew)
	(general
    (thickness 0.908)
  )
	(paper "A4")
	(title_block
    (title "HDMI-MIPI Bridge")
    (date "2024-04-24")
    (rev "1.3.2")
		(comment 9 "footprints 42-46 of 121")
	)
	(layers
    (0 "F.Cu" signal)
    (1 "In1.Cu" signal)
    (2 "In2.Cu" signal)
    (31 "B.Cu" signal)
    (32 "B.Adhes" user "B.Adhesive")
    (33 "F.Adhes" user "F.Adhesive")
    (34 "B.Paste" user)
    (35 "F.Paste" user)
    (36 "B.SilkS" user "B.Silkscreen")
    (37 "F.SilkS" user "F.Silkscreen")
    (38 "B.Mask" user)
    (39 "F.Mask" user)
    (40 "Dwgs.User" user "User.Drawings")
    (41 "Cmts.User" user "User.Comments")
    (42 "Eco1.User" user "User.Eco1")
    (43 "Eco2.User" user "User.Eco2")
    (44 "Edge.Cuts" user)
    (45 "Margin" user)
    (46 "B.CrtYd" user "B.Courtyard")
    (47 "F.CrtYd" user "F.Courtyard")
    (48 "B.Fab" user)
    (49 "F.Fab" user)
  )
	(footprint "antmicro-footprints:C_0402_1005Metric" (layer "F.Cu")
    (at 131 112.4)
    (descr "Capacitor SMD 0402")
    (tags "capacitor SMD 0402")
    (property "Author" "Antmicro")
    (property "Dielectric" "C0G")
    (property "License" "Apache-2.0")
    (property "MPN" "C0402C470J5GACTU")
    (property "Manufacturer" "KEMET")
    (property "Public" "False")
    (property "Sheetfile" "channel1.kicad_sch")
    (property "Sheetname" "Channel 1")
    (property "Val" "47p")
    (property "Voltage" "")
    (property "ki_description" "SMD Multilayer Ceramic Capacitor, 47 pF, 50 V, 0402 [1005 Metric], ± 5%, C0G / NP0, C Series KEMET")
    (property "ki_keywords" "0402, SMT, CAPACITOR, PASSIVE, CERAMIC, MLCC")
    (attr smd)
    (fp_text reference "C23" (at -1.6 7.6) (layer "F.SilkS")
        (effects (font (size 0.65 0.65) (thickness 0.13)) (justify left bottom))
    )
    (fp_text value "C_47p_0402" (at 0 1.4) (layer "F.Fab")
        (effects (font (size 0.65 0.65) (thickness 0.13)) (justify left bottom))
    )
    (fp_text user "License: Apache-2.0" (at -0.932 5.17) (layer "F.Fab") hide
        (effects (font (size 0.7 0.7) (thickness 0.15)) (justify left bottom))
    )
    (fp_text user "${REFERENCE}" (at -0.932 3.168) (layer "F.Fab") hide
        (effects (font (size 0.7 0.7) (thickness 0.15)) (justify left bottom))
    )
    (fp_text user "Author: Antmicro" (at -0.932 4.17) (layer "F.Fab") hide
        (effects (font (size 0.7 0.7) (thickness 0.15)) (justify left bottom))
    )
    (fp_rect (start -0.925 -0.47) (end 0.925 0.47)
      (stroke (width 0.05) (type default)) (fill none) (layer "F.CrtYd"))
    (fp_line (start -0.494 -0.25) (end 0.504 -0.25)
      (stroke (width 0.15) (type solid)) (layer "F.Fab"))
    (fp_line (start -0.494 0.248) (end -0.494 -0.25)
      (stroke (width 0.15) (type solid)) (layer "F.Fab"))
    (fp_line (start 0.504 -0.25) (end 0.504 0.248)
      (stroke (width 0.15) (type solid)) (layer "F.Fab"))
    (fp_line (start 0.504 0.248) (end -0.494 0.248)
      (stroke (width 0.15) (type solid)) (layer "F.Fab"))
    (pad "1" smd roundrect (at -0.48 0) (size 0.59 0.64) (layers "F.Cu" "F.Paste" "F.Mask") (roundrect_rratio 0.25)
      (net 2 "GND") (pintype "passive"))
    (pad "2" smd roundrect (at 0.48 0) (size 0.59 0.64) (layers "F.Cu" "F.Paste" "F.Mask") (roundrect_rratio 0.25)
      (net 15 "/Channel 1/CH1_REFCLK") (pintype "passive"))
  )
	(footprint "antmicro-footprints:C_0402_1005Metric" (layer "F.Cu")
    (at 163.79 110.85)
    (descr "Capacitor SMD 0402")
    (tags "capacitor SMD 0402")
    (property "Author" "Antmicro")
    (property "Dielectric" "")
    (property "License" "Apache-2.0")
    (property "MPN" "0402B471K250CT")
    (property "Manufacturer" "Walsin")
    (property "Public" "False")
    (property "Sheetfile" "channel2.kicad_sch")
    (property "Sheetname" "Channel 2")
    (property "Val" "470p")
    (property "Voltage" "")
    (property "ki_description" "SMD Multilayer Ceramic Capacitor, General Purpose, 470 pF, 25 V, 0402 [1005 Metric], ± 10%, X7R")
    (property "ki_keywords" "0402, SMT, CAPACITOR, PASSIVE, MLCC")
    (attr smd)
    (fp_text reference "C47" (at -3.69 6.85) (layer "F.SilkS")
        (effects (font (size 0.65 0.65) (thickness 0.13)) (justify left bottom))
    )
    (fp_text value "C_470p_0402" (at 0 1.4) (layer "F.Fab")
        (effects (font (size 0.65 0.65) (thickness 0.13)) (justify left bottom))
    )
    (fp_text user "License: Apache-2.0" (at -0.932 5.17) (layer "F.Fab") hide
        (effects (font (size 0.7 0.7) (thickness 0.15)) (justify left bottom))
    )
    (fp_text user "${REFERENCE}" (at -0.932 3.168) (layer "F.Fab") hide
        (effects (font (size 0.7 0.7) (thickness 0.15)) (justify left bottom))
    )
    (fp_text user "Author: Antmicro" (at -0.932 4.17) (layer "F.Fab") hide
        (effects (font (size 0.7 0.7) (thickness 0.15)) (justify left bottom))
    )
    (fp_rect (start -0.925 -0.47) (end 0.925 0.47)
      (stroke (width 0.05) (type default)) (fill none) (layer "F.CrtYd"))
    (fp_line (start -0.494 -0.25) (end 0.504 -0.25)
      (stroke (width 0.15) (type solid)) (layer "F.Fab"))
    (fp_line (start -0.494 0.248) (end -0.494 -0.25)
      (stroke (width 0.15) (type solid)) (layer "F.Fab"))
    (fp_line (start 0.504 -0.25) (end 0.504 0.248)
      (stroke (width 0.15) (type solid)) (layer "F.Fab"))
    (fp_line (start 0.504 0.248) (end -0.494 0.248)
      (stroke (width 0.15) (type solid)) (layer "F.Fab"))
    (pad "1" smd roundrect (at -0.48 0) (size 0.59 0.64) (layers "F.Cu" "F.Paste" "F.Mask") (roundrect_rratio 0.25)
      (net 32 "Net-(U4B-AVDD25)") (pintype "passive"))
    (pad "2" smd roundrect (at 0.48 0) (size 0.59 0.64) (layers "F.Cu" "F.Paste" "F.Mask") (roundrect_rratio 0.25)
      (net 2 "GND") (pintype "passive"))
  )
	(footprint "antmicro-footprints:Oscillator_SMD_TXC_7C_5x3.2x1.2mm" (layer "F.Cu")
    (at 126.79 110.01)
    (property "Author" "Antmicro")
    (property "License" "Apache-2.0")
    (property "MPN" "7C-27.000MBB-T")
    (property "Manufacturer" "TXC")
    (property "Public" "False")
    (property "Sheetfile" "channel1.kicad_sch")
    (property "Sheetname" "Channel 1")
    (property "Val" "27 MHz")
    (property "ki_description" "Oscillator, 27 MHz, 50 ppm, SMT, 5mm x 3.2mm, 3.3 V, 7C Series")
    (property "ki_keywords" "OSCILLATOR")
    (attr smd)
    (fp_text reference "Y1" (at 0.66 3.75 180) (layer "F.SilkS")
        (effects (font (size 0.65 0.65) (thickness 0.13)) (justify right bottom))
    )
    (fp_text value "Oscillator_27MHz_TXC_7C" (at -4.1148 3.4544) (layer "F.Fab")
        (effects (font (size 0.65 0.65) (thickness 0.13)) (justify left bottom))
    )
    (fp_text user "${REFERENCE}" (at -2.668 5.573) (layer "F.Fab") hide
        (effects (font (size 0.7 0.7) (thickness 0.15)) (justify left bottom))
    )
    (fp_text user "License: Apache-2.0" (at -2.668 7.972) (layer "F.Fab") hide
        (effects (font (size 0.7 0.7) (thickness 0.15)) (justify left bottom))
    )
    (fp_text user "Author: Antmicro" (at -2.668 6.773) (layer "F.Fab") hide
        (effects (font (size 0.7 0.7) (thickness 0.15)) (justify left bottom))
    )
    (fp_line (start -1.7 1.1) (end -1.7 -1.1)
      (stroke (width 0.12) (type solid)) (layer "F.SilkS"))
    (fp_line (start -0.4 -2.6) (end 0.4 -2.6)
      (stroke (width 0.12) (type solid)) (layer "F.SilkS"))
    (fp_line (start -0.4 2.6) (end 0.4 2.6)
      (stroke (width 0.12) (type solid)) (layer "F.SilkS"))
    (fp_line (start 1.7 1.1) (end 1.7 -1.1)
      (stroke (width 0.12) (type solid)) (layer "F.SilkS"))
    (fp_circle (center -1.8438 -2.2532) (end -1.8438 -2.2032)
      (stroke (width 0.15) (type solid)) (fill solid) (layer "F.SilkS"))
    (fp_rect (start -1.9 -2.85) (end 1.9 2.8)
      (stroke (width 0.05) (type solid)) (fill none) (layer "F.CrtYd"))
    (pad "1" smd rect (at -1.099 -1.9 270) (size 1.4 1.2) (layers "F.Cu" "F.Paste" "F.Mask")
      (net 10 "Net-(Y1-EN)") (pinfunction "EN") (pintype "input"))
    (pad "2" smd rect (at -1.1 1.9 270) (size 1.4 1.2) (layers "F.Cu" "F.Paste" "F.Mask")
      (net 2 "GND") (pinfunction "GND") (pintype "power_in"))
    (pad "3" smd rect (at 1.099 1.9 270) (size 1.4 1.2) (layers "F.Cu" "F.Paste" "F.Mask")
      (net 13 "Net-(Y1-OUT)") (pinfunction "OUT") (pintype "output"))
    (pad "4" smd rect (at 1.1 -1.9 270) (size 1.4 1.2) (layers "F.Cu" "F.Paste" "F.Mask")
      (net 10 "Net-(Y1-EN)") (pinfunction "VDD") (pintype "power_in"))
  )
	(footprint "antmicro-footprints:R_0402_1005Metric" (layer "F.Cu")
    (at 145.1 108.085 -90)
    (descr "Resistor SMD 0402")
    (tags "resistor SMD 0402")
    (property "Author" "Antmicro")
    (property "License" "Apache-2.0")
    (property "MPN" "CR0402-FX-1002GLF")
    (property "Manufacturer" "Bourns")
    (property "Public" "False")
    (property "Sheetfile" "channel1.kicad_sch")
    (property "Sheetname" "Channel 1")
    (property "Tolerance" "1%")
    (property "Val" "10k")
    (property "ki_description" "SMD Chip Resistor, 10 kohm, ± 1%, 62.5 mW, 0402 [1005 Metric], Thick Film, General Purpose")
    (property "ki_keywords" "0402, SMT, RESISTOR, PASSIVE")
    (attr smd)
    (fp_text reference "R9" (at -1.035 -1.5 -90) (layer "F.SilkS")
        (effects (font (size 0.65 0.65) (thickness 0.13)) (justify left bottom))
    )
    (fp_text value "R_10k_0402" (at 0 1.4 -90) (layer "F.Fab")
        (effects (font (size 0.65 0.65) (thickness 0.13)) (justify left bottom))
    )
    (fp_text user "${REFERENCE}" (at -0.95 3.168 -90) (layer "F.Fab") hide
        (effects (font (size 0.7 0.7) (thickness 0.15)) (justify left bottom))
    )
    (fp_text user "License: Apache-2.0" (at -0.95 5.169 -90) (layer "F.Fab") hide
        (effects (font (size 0.7 0.7) (thickness 0.15)) (justify left bottom))
    )
    (fp_text user "Author: Antmicro" (at -0.95 4.169 -90) (layer "F.Fab") hide
        (effects (font (size 0.7 0.7) (thickness 0.15)) (justify left bottom))
    )
    (fp_rect (start -0.925 -0.47) (end 0.925 0.47)
      (stroke (width 0.05) (type default)) (fill none) (layer "F.CrtYd"))
    (fp_rect (start -0.5 -0.25) (end 0.5 0.25)
      (stroke (width 0.15) (type solid)) (fill none) (layer "F.Fab"))
    (pad "1" smd roundrect (at -0.48 0 270) (size 0.59 0.64) (layers "F.Cu" "F.Paste" "F.Mask") (roundrect_rratio 0.25)
      (net 104 "/Channel 1/HDMI1_DDC_SDA_3V3") (pintype "passive"))
    (pad "2" smd roundrect (at 0.48 0 270) (size 0.59 0.64) (layers "F.Cu" "F.Paste" "F.Mask") (roundrect_rratio 0.25)
      (net 9 "+3V3") (pintype "passive"))
  )
	(footprint "antmicro-footprints:R_0402_1005Metric" (layer "F.Cu")
    (at 131 111.4)
    (descr "Resistor SMD 0402")
    (tags "resistor SMD 0402")
    (property "Author" "Antmicro")
    (property "License" "Apache-2.0")
    (property "MPN" "CR0402-FX-22R0GLF")
    (property "Manufacturer" "Bourns")
    (property "Public" "False")
    (property "Sheetfile" "channel1.kicad_sch")
    (property "Sheetname" "Channel 1")
    (property "Tolerance" "1%")
    (property "Val" "22R")
    (property "ki_description" "SMD Chip Resistor, 22 ohm, ± 1%, 62.5 mW, 0402 [1005 Metric], Thick Film, General Purpose")
    (property "ki_keywords" "0402, SMT, RESISTOR, PASSIVE")
    (attr smd)
    (fp_text reference "R13" (at -1.6 7.6) (layer "F.SilkS")
        (effects (font (size 0.65 0.65) (thickness 0.13)) (justify left bottom))
    )
    (fp_text value "R_22R_0402" (at 0 1.4) (layer "F.Fab")
        (effects (font (size 0.65 0.65) (thickness 0.13)) (justify left bottom))
    )
    (fp_text user "License: Apache-2.0" (at -0.95 5.169) (layer "F.Fab") hide
        (effects (font (size 0.7 0.7) (thickness 0.15)) (justify left bottom))
    )
    (fp_text user "Author: Antmicro" (at -0.95 4.169) (layer "F.Fab") hide
        (effects (font (size 0.7 0.7) (thickness 0.15)) (justify left bottom))
    )
    (fp_text user "${REFERENCE}" (at -0.95 3.168) (layer "F.Fab") hide
        (effects (font (size 0.7 0.7) (thickness 0.15)) (justify left bottom))
    )
    (fp_rect (start -0.925 -0.47) (end 0.925 0.47)
      (stroke (width 0.05) (type default)) (fill none) (layer "F.CrtYd"))
    (fp_rect (start -0.5 -0.25) (end 0.5 0.25)
      (stroke (width 0.15) (type solid)) (fill none) (layer "F.Fab"))
    (pad "1" smd roundrect (at -0.48 0) (size 0.59 0.64) (layers "F.Cu" "F.Paste" "F.Mask") (roundrect_rratio 0.25)
      (net 13 "Net-(Y1-OUT)") (pintype "passive"))
    (pad "2" smd roundrect (at 0.48 0) (size 0.59 0.64) (layers "F.Cu" "F.Paste" "F.Mask") (roundrect_rratio 0.25)
      (net 15 "/Channel 1/CH1_REFCLK") (pintype "passive"))
  )
)
